# SCM (Grand Teton) — schematic netlist excerpt (pin names and nets, part order shuffled) for the footprints in the layout excerpt that follows; sources: Cadence DE-HDL packaged netlist, KiCad conversion of 12092022_DA0F0TMDCD0_F0T_Management_Board_D_brd_V3_OCP.brd

R3  Q_RES  0 5% CHIP  pkg 0402LF  page 20 : A = M_BMC_DDR4_ZQU ; B = GND
R749  Q_RES  4.7K 1% CHIP  pkg 0402LF  page 42 : A = P3V3_AUX ; B = FM_BMC_CRASHLOG_TRIG_N

(kicad_pcb
	(version 20260206)
	(generator "pcbnew")
	(generator_version "10.0")
	(general
		(thickness 1.6)
		(legacy_teardrops no)
	)
	(paper "A4")
	(title_block
		(title "12092022_DA0F0TMDCD0_F0T_Management_Board_D_brd_V3_OCP.brd")
		(comment 1 "Grand Teton / footprints 1263-1264 of 1440")
	)
	(layers
		(0 "F.Cu" signal "TOP")
		(4 "In1.Cu" signal "GND")
		(6 "In2.Cu" signal "IN1")
		(8 "In3.Cu" signal "GND1")
		(10 "In4.Cu" signal "IN2")
		(12 "In5.Cu" signal "VCC")
		(14 "In6.Cu" signal "VCC1")
		(16 "In7.Cu" signal "IN3")
		(18 "In8.Cu" signal "GND2")
		(20 "In9.Cu" signal "IN4")
		(22 "In10.Cu" signal "GND3")
		(2 "B.Cu" signal "BOTTOM")
		(9 "F.Adhes" user "F.Adhesive")
		(11 "B.Adhes" user "B.Adhesive")
		(13 "F.Paste" user "Package Geometry/Pastemask Top")
		(15 "B.Paste" user "Package Geometry/Pastemask Bottom")
		(5 "F.SilkS" user "Ref Des/Silkscreen Top")
		(7 "B.SilkS" user "Ref Des/Silkscreen Bottom")
		(1 "F.Mask" user "Board Geometry/Soldermask Top")
		(3 "B.Mask" user "Board Geometry/Soldermask Bottom")
		(17 "Dwgs.User" user "User.Drawings")
		(19 "Cmts.User" user "User.Comments")
		(21 "Eco1.User" user "User.Eco1")
		(23 "Eco2.User" user "User.Eco2")
		(25 "Edge.Cuts" user "Board Geometry/Outline")
		(27 "Margin" user)
		(31 "F.CrtYd" user "Package Geometry/Place Bound Top")
		(29 "B.CrtYd" user "Package Geometry/Place Bound Bottom")
		(35 "F.Fab" user "Ref Des/Assembly Top")
		(33 "B.Fab" user "Ref Des/Assembly Bottom")
	)
	(footprint ""
		(layer "B.Cu")
		(at 20.955 -101.981 -90)
		(property "Reference" "R749"
			(at 0 0 90)
			(layer "B.SilkS")
			(hide yes)
			(effects
				(font
					(size 1.27 1.27)
				)
				(justify mirror)
			)
		)
		(property "Value" ""
			(at 0 0 90)
			(layer "B.Fab")
			(effects
				(font
					(size 1.27 1.27)
				)
				(justify mirror)
			)
		)
		(duplicate_pad_numbers_are_jumpers no)
		(fp_line
			(start -0.7874 0.4064)
			(end 0.7874 0.4064)
			(stroke
				(width 0.1524)
				(type default)
			)
			(layer "B.SilkS")
		)
		(fp_line
			(start 0.7874 0.4064)
			(end 0.7874 -0.4064)
			(stroke
				(width 0.1524)
				(type default)
			)
			(layer "B.SilkS")
		)
		(fp_line
			(start -0.7874 -0.4064)
			(end -0.7874 0.4064)
			(stroke
				(width 0.1524)
				(type default)
			)
			(layer "B.SilkS")
		)
		(fp_line
			(start 0.7874 -0.4064)
			(end -0.7874 -0.4064)
			(stroke
				(width 0.1524)
				(type default)
			)
			(layer "B.SilkS")
		)
		(fp_line
			(start -0.67945 0.3048)
			(end -0.120396 0.3048)
			(stroke
				(width 0.1)
				(type default)
			)
			(layer "B.Fab")
		)
		(fp_line
			(start -0.120396 0.3048)
			(end -0.120396 0.2794)
			(stroke
				(width 0.1)
				(type default)
			)
			(layer "B.Fab")
		)
		(fp_line
			(start 0.12065 0.3048)
			(end 0.67945 0.3048)
			(stroke
				(width 0.1)
				(type default)
			)
			(layer "B.Fab")
		)
		(fp_line
			(start 0.67945 0.3048)
			(end 0.67945 -0.305054)
			(stroke
				(width 0.1)
				(type default)
			)
			(layer "B.Fab")
		)
		(fp_line
			(start -0.120396 0.2794)
			(end 0.12065 0.2794)
			(stroke
				(width 0.1)
				(type default)
			)
			(layer "B.Fab")
		)
		(fp_line
			(start 0.12065 0.2794)
			(end 0.12065 0.3048)
			(stroke
				(width 0.1)
				(type default)
			)
			(layer "B.Fab")
		)
		(fp_line
			(start -0.12065 -0.2794)
			(end -0.12065 -0.3048)
			(stroke
				(width 0.1)
				(type default)
			)
			(layer "B.Fab")
		)
		(fp_line
			(start 0.12065 -0.2794)
			(end -0.12065 -0.2794)
			(stroke
				(width 0.1)
				(type default)
			)
			(layer "B.Fab")
		)
		(fp_line
			(start -0.67945 -0.3048)
			(end -0.67945 0.3048)
			(stroke
				(width 0.1)
				(type default)
			)
			(layer "B.Fab")
		)
		(fp_line
			(start -0.12065 -0.3048)
			(end -0.67945 -0.3048)
			(stroke
				(width 0.1)
				(type default)
			)
			(layer "B.Fab")
		)
		(fp_line
			(start 0.12065 -0.305054)
			(end 0.12065 -0.2794)
			(stroke
				(width 0.1)
				(type default)
			)
			(layer "B.Fab")
		)
		(fp_line
			(start 0.67945 -0.305054)
			(end 0.12065 -0.305054)
			(stroke
				(width 0.1)
				(type default)
			)
			(layer "B.Fab")
		)
		(pad "1" smd circle
			(at 0.40005 0 90)
			(size 0 0)
			(layers "B.Cu" "B.Mask" "B.Paste")
			(net "P3V3_AUX")
		)
		(pad "2" smd circle
			(at -0.40005 0 90)
			(size 0 0)
			(layers "B.Cu" "B.Mask" "B.Paste")
			(net "FM_BMC_CRASHLOG_TRIG_N")
		)
	)
	(footprint ""
		(layer "B.Cu")
		(at 78.02372 -51.000406 180)
		(property "Reference" "R3"
			(at 0 0 0)
			(layer "B.SilkS")
			(hide yes)
			(effects
				(font
					(size 1.27 1.27)
				)
				(justify mirror)
			)
		)
		(property "Value" ""
			(at 0 0 0)
			(layer "B.Fab")
			(effects
				(font
					(size 1.27 1.27)
				)
				(justify mirror)
			)
		)
		(duplicate_pad_numbers_are_jumpers no)
		(fp_line
			(start 0.7874 0.4064)
			(end 0.7874 -0.4064)
			(stroke
				(width 0.1524)
				(type default)
			)
			(layer "B.SilkS")
		)
		(fp_line
			(start 0.7874 -0.4064)
			(end -0.7874 -0.4064)
			(stroke
				(width 0.1524)
				(type default)
			)
			(layer "B.SilkS")
		)
		(fp_line
			(start -0.7874 0.4064)
			(end 0.7874 0.4064)
			(stroke
				(width 0.1524)
				(type default)
			)
			(layer "B.SilkS")
		)
		(fp_line
			(start -0.7874 -0.4064)
			(end -0.7874 0.4064)
			(stroke
				(width 0.1524)
				(type default)
			)
			(layer "B.SilkS")
		)
		(fp_line
			(start 0.67945 0.3048)
			(end 0.67945 -0.305054)
			(stroke
				(width 0.1)
				(type default)
			)
			(layer "B.Fab")
		)
		(fp_line
			(start 0.67945 -0.305054)
			(end 0.12065 -0.305054)
			(stroke
				(width 0.1)
				(type default)
			)
			(layer "B.Fab")
		)
		(fp_line
			(start 0.12065 0.3048)
			(end 0.67945 0.3048)
			(stroke
				(width 0.1)
				(type default)
			)
			(layer "B.Fab")
		)
		(fp_line
			(start 0.12065 0.2794)
			(end 0.12065 0.3048)
			(stroke
				(width 0.1)
				(type default)
			)
			(layer "B.Fab")
		)
		(fp_line
			(start 0.12065 -0.2794)
			(end -0.12065 -0.2794)
			(stroke
				(width 0.1)
				(type default)
			)
			(layer "B.Fab")
		)
		(fp_line
			(start 0.12065 -0.305054)
			(end 0.12065 -0.2794)
			(stroke
				(width 0.1)
				(type default)
			)
			(layer "B.Fab")
		)
		(fp_line
			(start -0.120396 0.3048)
			(end -0.120396 0.2794)
			(stroke
				(width 0.1)
				(type default)
			)
			(layer "B.Fab")
		)
		(fp_line
			(start -0.120396 0.2794)
			(end 0.12065 0.2794)
			(stroke
				(width 0.1)
				(type default)
			)
			(layer "B.Fab")
		)
		(fp_line
			(start -0.12065 -0.2794)
			(end -0.12065 -0.3048)
			(stroke
				(width 0.1)
				(type default)
			)
			(layer "B.Fab")
		)
		(fp_line
			(start -0.12065 -0.3048)
			(end -0.67945 -0.3048)
			(stroke
				(width 0.1)
				(type default)
			)
			(layer "B.Fab")
		)
		(fp_line
			(start -0.67945 0.3048)
			(end -0.120396 0.3048)
			(stroke
				(width 0.1)
				(type default)
			)
			(layer "B.Fab")
		)
		(fp_line
			(start -0.67945 -0.3048)
			(end -0.67945 0.3048)
			(stroke
				(width 0.1)
				(type default)
			)
			(layer "B.Fab")
		)
		(pad "1" smd circle
			(at 0.40005 0)
			(size 0 0)
			(layers "B.Cu" "B.Mask" "B.Paste")
			(net "M_BMC_DDR4_ZQU")
		)
		(pad "2" smd circle
			(at -0.40005 0)
			(size 0 0)
			(layers "B.Cu" "B.Mask" "B.Paste")
			(net "GND")
		)
	)
)
